(kicad_pcb
	(version 20260206)
	(generator "pcbnew")
	(generator_version "10.0")
	(general
		(thickness 1.6)
		(legacy_teardrops no)
	)
	(paper "A4")
	(title_block
		(title "baseboard — 13948-1b.1110WZS1818.brd")
		(comment 1 "Honey Badger (Wiwynn) / footprints 319-325 of 2523")
	)
	(layers
		(0 "F.Cu" signal "TOP")
		(4 "In1.Cu" signal "L2GND")
		(6 "In2.Cu" signal "L3")
		(8 "In3.Cu" signal "L4VCC")
		(10 "In4.Cu" signal "L5VCC")
		(12 "In5.Cu" signal "L6")
		(14 "In6.Cu" signal "L7GND")
		(2 "B.Cu" signal "BOTTOM")
		(9 "F.Adhes" user "F.Adhesive")
		(11 "B.Adhes" user "B.Adhesive")
		(13 "F.Paste" user "Package Geometry/Pastemask Top")
		(15 "B.Paste" user "Package Geometry/Pastemask Bottom")
		(5 "F.SilkS" user "Ref Des/Silkscreen Top")
		(7 "B.SilkS" user "Ref Des/Silkscreen Bottom")
		(1 "F.Mask" user "Board Geometry/Soldermask Top")
		(3 "B.Mask" user "Board Geometry/Soldermask Bottom")
		(17 "Dwgs.User" user "User.Drawings")
		(19 "Cmts.User" user "User.Comments")
		(21 "Eco1.User" user "User.Eco1")
		(23 "Eco2.User" user "User.Eco2")
		(25 "Edge.Cuts" user "Board Geometry/Outline")
		(27 "Margin" user)
		(31 "F.CrtYd" user "Package Geometry/Place Bound Top")
		(29 "B.CrtYd" user "Package Geometry/Place Bound Bottom")
		(35 "F.Fab" user "Ref Des/Assembly Top")
		(33 "B.Fab" user "Ref Des/Assembly Bottom")
	)
	(footprint ""
		(layer "F.Cu")
		(at 54.991 -109.982 180)
		(property "Reference" "SC1306"
			(at 0 0 180)
			(layer "F.SilkS")
			(hide yes)
			(effects
				(font
					(size 1.27 1.27)
				)
			)
		)
		(property "Value" "SCD1U16V2KX-3GP"
			(at 1.1811 -2.7051 180)
			(unlocked yes)
			(layer "F.Fab")
			(hide yes)
			(effects
				(font
					(size 1.016 1.016)
					(thickness 0.1524)
				)
			)
		)
		(property "Device Type" "C402H22"
			(at 1.1811 -4.2291 180)
			(unlocked yes)
			(layer "F.Fab")
			(hide yes)
			(effects
				(font
					(size 1.016 1.016)
					(thickness 0.1524)
				)
			)
		)
		(duplicate_pad_numbers_are_jumpers no)
		(fp_rect
			(start -0.4318 0.9525)
			(end 0.4318 -0.9525)
			(stroke
				(width 0)
				(type default)
			)
			(fill no)
			(layer "F.CrtYd")
		)
		(fp_rect
			(start -0.4318 0.9525)
			(end 0.4318 -0.9525)
			(stroke
				(width 0)
				(type default)
			)
			(fill no)
			(layer "F.Fab")
		)
		(pad "1" smd custom
			(at 0 -0.4445 180)
			(size 0.1524 0.1524)
			(layers "F.Cu" "F.Mask" "F.Paste")
			(net "P5V_STBY")
			(options
				(clearance outline)
				(anchor circle)
			)
			(primitives
				(gr_poly
					(pts
						(arc
							(start 0.3048 -0.2032)
							(mid 0.275042 -0.275042)
							(end 0.2032 -0.3048)
						)
						(arc
							(start -0.2032 -0.3048)
							(mid -0.275042 -0.275042)
							(end -0.3048 -0.2032)
						)
						(arc
							(start -0.3048 0.2032)
							(mid -0.275042 0.275042)
							(end -0.2032 0.3048)
						)
						(arc
							(start 0.2032 0.3048)
							(mid 0.275042 0.275042)
							(end 0.3048 0.2032)
						)
					)
					(width 0)
					(fill yes)
				)
			)
		)
		(pad "2" smd custom
			(at 0 0.4445 180)
			(size 0.1524 0.1524)
			(layers "F.Cu" "F.Mask" "F.Paste")
			(net "GND")
			(options
				(clearance outline)
				(anchor circle)
			)
			(primitives
				(gr_poly
					(pts
						(arc
							(start 0.3048 -0.2032)
							(mid 0.275042 -0.275042)
							(end 0.2032 -0.3048)
						)
						(arc
							(start -0.2032 -0.3048)
							(mid -0.275042 -0.275042)
							(end -0.3048 -0.2032)
						)
						(arc
							(start -0.3048 0.2032)
							(mid -0.275042 0.275042)
							(end -0.2032 0.3048)
						)
						(arc
							(start 0.2032 0.3048)
							(mid 0.275042 0.275042)
							(end 0.3048 0.2032)
						)
					)
					(width 0)
					(fill yes)
				)
			)
		)
	)
	(footprint ""
		(layer "F.Cu")
		(at 317.754 -113.03 90)
		(property "Reference" "PG3"
			(at 0 0 90)
			(layer "F.SilkS")
			(hide yes)
			(effects
				(font
					(size 1.27 1.27)
				)
			)
		)
		(property "Value" "COPPER-CLOSE-GP-U"
			(at 0.0762 -2.8702 90)
			(unlocked yes)
			(layer "F.Fab")
			(hide yes)
			(effects
				(font
					(size 1.016 1.016)
					(thickness 0.1524)
				)
			)
		)
		(property "Device Type" "CON2C-U"
			(at 0.0762 -4.3942 90)
			(unlocked yes)
			(layer "F.Fab")
			(hide yes)
			(effects
				(font
					(size 1.016 1.016)
					(thickness 0.1524)
				)
			)
		)
		(duplicate_pad_numbers_are_jumpers no)
		(fp_rect
			(start -0.9398 0.9652)
			(end 0.9398 -0.9652)
			(stroke
				(width 0)
				(type default)
			)
			(fill no)
			(layer "F.CrtYd")
		)
		(fp_rect
			(start -0.9398 0.9652)
			(end 0.9398 -0.9652)
			(stroke
				(width 0)
				(type default)
			)
			(fill no)
			(layer "F.Fab")
		)
		(pad "1" smd custom
			(at 0 -0.5334 90)
			(size 0.17145 0.17145)
			(layers "F.Cu" "F.Mask" "F.Paste")
			(net "AGND_P3V3_STBY")
			(options
				(clearance outline)
				(anchor circle)
			)
			(primitives
				(gr_poly
					(pts
						(xy -0.127 0.3429) (xy -0.127 0.1651) (xy -0.635 -0.3429) (xy 0.635 -0.3429) (xy 0.127 0.1651)
						(xy 0.127 0.3429)
					)
					(width 0)
					(fill yes)
				)
			)
		)
		(pad "2" smd custom
			(at 0 0.5334 90)
			(size 0.17145 0.17145)
			(layers "F.Cu" "F.Mask" "F.Paste")
			(net "GND")
			(options
				(clearance outline)
				(anchor circle)
			)
			(primitives
				(gr_poly
					(pts
						(xy -0.635 0.3429) (xy -0.127 -0.1651) (xy -0.127 -0.3429) (xy 0.127 -0.3429) (xy 0.127 -0.1651)
						(xy 0.635 0.3429)
					)
					(width 0)
					(fill yes)
				)
			)
		)
	)
	(footprint ""
		(layer "F.Cu")
		(at 303.701958 -58.928 180)
		(property "Reference" "C286"
			(at 0 0 180)
			(layer "F.SilkS")
			(hide yes)
			(effects
				(font
					(size 1.27 1.27)
				)
			)
		)
		(property "Value" "SCD1U25V2KX-2-GP"
			(at 1.1811 -2.7051 180)
			(unlocked yes)
			(layer "F.Fab")
			(hide yes)
			(effects
				(font
					(size 1.016 1.016)
					(thickness 0.1524)
				)
			)
		)
		(property "Device Type" "C402H22"
			(at 1.1811 -4.2291 180)
			(unlocked yes)
			(layer "F.Fab")
			(hide yes)
			(effects
				(font
					(size 1.016 1.016)
					(thickness 0.1524)
				)
			)
		)
		(duplicate_pad_numbers_are_jumpers no)
		(fp_rect
			(start -0.4318 0.9525)
			(end 0.4318 -0.9525)
			(stroke
				(width 0)
				(type default)
			)
			(fill no)
			(layer "F.CrtYd")
		)
		(fp_rect
			(start -0.4318 0.9525)
			(end 0.4318 -0.9525)
			(stroke
				(width 0)
				(type default)
			)
			(fill no)
			(layer "F.Fab")
		)
		(pad "1" smd custom
			(at 0 -0.4445 180)
			(size 0.1524 0.1524)
			(layers "F.Cu" "F.Mask" "F.Paste")
			(net "P3V3")
			(options
				(clearance outline)
				(anchor circle)
			)
			(primitives
				(gr_poly
					(pts
						(arc
							(start 0.3048 -0.2032)
							(mid 0.275042 -0.275042)
							(end 0.2032 -0.3048)
						)
						(arc
							(start -0.2032 -0.3048)
							(mid -0.275042 -0.275042)
							(end -0.3048 -0.2032)
						)
						(arc
							(start -0.3048 0.2032)
							(mid -0.275042 0.275042)
							(end -0.2032 0.3048)
						)
						(arc
							(start 0.2032 0.3048)
							(mid 0.275042 0.275042)
							(end 0.3048 0.2032)
						)
					)
					(width 0)
					(fill yes)
				)
			)
		)
		(pad "2" smd custom
			(at 0 0.4445 180)
			(size 0.1524 0.1524)
			(layers "F.Cu" "F.Mask" "F.Paste")
			(net "GND")
			(options
				(clearance outline)
				(anchor circle)
			)
			(primitives
				(gr_poly
					(pts
						(arc
							(start 0.3048 -0.2032)
							(mid 0.275042 -0.275042)
							(end 0.2032 -0.3048)
						)
						(arc
							(start -0.2032 -0.3048)
							(mid -0.275042 -0.275042)
							(end -0.3048 -0.2032)
						)
						(arc
							(start -0.3048 0.2032)
							(mid -0.275042 0.275042)
							(end -0.2032 0.3048)
						)
						(arc
							(start 0.2032 0.3048)
							(mid 0.275042 0.275042)
							(end 0.3048 0.2032)
						)
					)
					(width 0)
					(fill yes)
				)
			)
		)
	)
	(footprint ""
		(layer "F.Cu")
		(at 111.322612 -204.978)
		(property "Reference" "SR881"
			(at 0 0 0)
			(layer "F.SilkS")
			(hide yes)
			(effects
				(font
					(size 1.27 1.27)
				)
			)
		)
		(property "Value" "0R2J-2-GP"
			(at 0.064008 -3.993896 0)
			(unlocked yes)
			(layer "F.Fab")
			(hide yes)
			(effects
				(font
					(size 1.016 1.016)
					(thickness 0.1524)
				)
			)
		)
		(property "Device Type" "R402H16"
			(at 0.064008 -5.517896 0)
			(unlocked yes)
			(layer "F.Fab")
			(hide yes)
			(effects
				(font
					(size 1.016 1.016)
					(thickness 0.1524)
				)
			)
		)
		(duplicate_pad_numbers_are_jumpers no)
		(fp_line
			(start -0.508 -0.9398)
			(end -0.508 0.9398)
			(stroke
				(width 0.1524)
				(type default)
			)
			(layer "F.SilkS")
		)
		(fp_line
			(start 0.508 -0.9398)
			(end -0.508 -0.9398)
			(stroke
				(width 0.1524)
				(type default)
			)
			(layer "F.SilkS")
		)
		(fp_rect
			(start -0.508 0.9398)
			(end 0.508 -0.9398)
			(stroke
				(width 0)
				(type default)
			)
			(fill no)
			(layer "F.CrtYd")
		)
		(fp_rect
			(start -0.508 0.9398)
			(end 0.508 -0.9398)
			(stroke
				(width 0)
				(type default)
			)
			(fill no)
			(layer "F.Fab")
		)
		(pad "1" smd custom
			(at 0 -0.4445)
			(size 0.1397 0.1397)
			(layers "F.Cu" "F.Mask" "F.Paste")
			(net "SAS_HDD_REDV_TX8_N")
			(options
				(clearance outline)
				(anchor circle)
			)
			(primitives
				(gr_poly
					(pts
						(arc
							(start -0.1778 -0.2794)
							(mid -0.249642 -0.249642)
							(end -0.2794 -0.1778)
						)
						(arc
							(start -0.2794 0.1778)
							(mid -0.249642 0.249642)
							(end -0.1778 0.2794)
						)
						(arc
							(start 0.1778 0.2794)
							(mid 0.249642 0.249642)
							(end 0.2794 0.1778)
						)
						(arc
							(start 0.2794 -0.1778)
							(mid 0.249642 -0.249642)
							(end 0.1778 -0.2794)
						)
					)
					(width 0)
					(fill yes)
				)
			)
		)
		(pad "2" smd custom
			(at 0 0.4445)
			(size 0.1397 0.1397)
			(layers "F.Cu" "F.Mask" "F.Paste")
			(net "SAS_HDD_REDV_SER_TX8_N")
			(options
				(clearance outline)
				(anchor circle)
			)
			(primitives
				(gr_poly
					(pts
						(arc
							(start -0.1778 -0.2794)
							(mid -0.249642 -0.249642)
							(end -0.2794 -0.1778)
						)
						(arc
							(start -0.2794 0.1778)
							(mid -0.249642 0.249642)
							(end -0.1778 0.2794)
						)
						(arc
							(start 0.1778 0.2794)
							(mid 0.249642 0.249642)
							(end 0.2794 0.1778)
						)
						(arc
							(start 0.2794 -0.1778)
							(mid 0.249642 -0.249642)
							(end 0.1778 -0.2794)
						)
					)
					(width 0)
					(fill yes)
				)
			)
		)
	)
	(footprint ""
		(layer "F.Cu")
		(at 330.581 -102.616)
		(property "Reference" "PL3"
			(at 0 0 0)
			(layer "F.SilkS")
			(hide yes)
			(effects
				(font
					(size 1.27 1.27)
				)
			)
		)
		(property "Value" "COIL-3D3UH-36-GP"
			(at -5.6134 -2.4892 0)
			(unlocked yes)
			(layer "F.Fab")
			(hide yes)
			(effects
				(font
					(size 1.016 1.016)
					(thickness 0.1524)
				)
			)
		)
		(property "Device Type" "L7166-1830-UH197"
			(at -5.6134 -4.0132 0)
			(unlocked yes)
			(layer "F.Fab")
			(hide yes)
			(effects
				(font
					(size 1.016 1.016)
					(thickness 0.1524)
				)
			)
		)
		(duplicate_pad_numbers_are_jumpers no)
		(fp_line
			(start -3.556 -4.5466)
			(end 3.556 -4.5466)
			(stroke
				(width 0.1524)
				(type default)
			)
			(layer "F.SilkS")
		)
		(fp_line
			(start -3.556 4.5466)
			(end -3.556 -4.5466)
			(stroke
				(width 0.1524)
				(type default)
			)
			(layer "F.SilkS")
		)
		(fp_line
			(start 3.556 -4.5466)
			(end 3.556 4.5466)
			(stroke
				(width 0.1524)
				(type default)
			)
			(layer "F.SilkS")
		)
		(fp_line
			(start 3.556 4.5466)
			(end -3.556 4.5466)
			(stroke
				(width 0.1524)
				(type default)
			)
			(layer "F.SilkS")
		)
		(fp_rect
			(start -3.302 3.5306)
			(end 3.302 -3.5306)
			(stroke
				(width 0)
				(type default)
			)
			(fill no)
			(layer "F.CrtYd")
		)
		(fp_poly
			(pts
				(xy -3.81 4.6228) (xy -3.81 -2.3241) (xy -3.302 -2.3241) (xy -3.302 3.5306) (xy 3.302 3.5306) (xy 3.302 -3.5306)
				(xy -3.302 -3.5306) (xy -3.302 -2.3368) (xy -3.81 -2.3368) (xy -3.81 -4.6228) (xy 3.81 -4.6228)
				(xy 3.81 4.6228)
			)
			(stroke
				(width 0)
				(type default)
			)
			(fill no)
			(layer "F.CrtYd")
		)
		(fp_rect
			(start -3.81 4.6228)
			(end 3.81 -4.6228)
			(stroke
				(width 0)
				(type default)
			)
			(fill no)
			(layer "F.Fab")
		)
		(pad "1" smd rect
			(at 0 -2.804922)
			(size 3.5052 2.9718)
			(layers "F.Cu" "F.Mask" "F.Paste")
			(net "P3V3_STBY_LL")
		)
		(pad "2" smd rect
			(at 0 2.804922)
			(size 3.5052 2.9718)
			(layers "F.Cu" "F.Mask" "F.Paste")
			(net "P3V3_STBY")
		)
	)
	(footprint ""
		(layer "F.Cu")
		(at 51.308 -201.422 -90)
		(property "Reference" "Q94"
			(at 0 0 270)
			(layer "F.SilkS")
			(hide yes)
			(effects
				(font
					(size 1.27 1.27)
				)
			)
		)
		(property "Value" "2N7002A-7-GP"
			(at 0.127 -8.9662 270)
			(unlocked yes)
			(layer "F.Fab")
			(hide yes)
			(effects
				(font
					(size 1.016 1.016)
					(thickness 0.1524)
				)
			)
		)
		(property "Device Type" "SOT23DGS2D4H48"
			(at 0.127 -10.4902 270)
			(unlocked yes)
			(layer "F.Fab")
			(hide yes)
			(effects
				(font
					(size 1.016 1.016)
					(thickness 0.1524)
				)
			)
		)
		(duplicate_pad_numbers_are_jumpers no)
		(fp_line
			(start -1.651 1.778)
			(end 1.651 1.778)
			(stroke
				(width 0.1524)
				(type default)
			)
			(layer "F.SilkS")
		)
		(fp_line
			(start 1.651 1.778)
			(end 1.651 -1.778)
			(stroke
				(width 0.1524)
				(type default)
			)
			(layer "F.SilkS")
		)
		(fp_line
			(start -1.651 -1.778)
			(end -1.651 1.778)
			(stroke
				(width 0.1524)
				(type default)
			)
			(layer "F.SilkS")
		)
		(fp_line
			(start 1.651 -1.778)
			(end -1.651 -1.778)
			(stroke
				(width 0.1524)
				(type default)
			)
			(layer "F.SilkS")
		)
		(fp_poly
			(pts
				(xy -1.778 1.8796) (xy -1.778 -1.8796) (xy 1.778 -1.8796) (xy 1.778 1.8796)
			)
			(stroke
				(width 0)
				(type default)
			)
			(fill no)
			(layer "F.CrtYd")
		)
		(fp_poly
			(pts
				(xy -1.778 1.8796) (xy -1.778 -1.8796) (xy 1.778 -1.8796) (xy 1.778 1.8796)
			)
			(stroke
				(width 0)
				(type default)
			)
			(fill no)
			(layer "F.Fab")
		)
		(pad "D" smd custom
			(at 0 -0.9525 270)
			(size 0.1905 0.1905)
			(layers "F.Cu" "F.Mask" "F.Paste")
			(net "MATED_P12V_EN")
			(options
				(clearance outline)
				(anchor circle)
			)
			(primitives
				(gr_poly
					(pts
						(arc
							(start -0.1778 0.5715)
							(mid -0.321484 0.511984)
							(end -0.381 0.3683)
						)
						(arc
							(start -0.381 -0.3683)
							(mid -0.321484 -0.511984)
							(end -0.1778 -0.5715)
						)
						(arc
							(start 0.1778 -0.5715)
							(mid 0.321484 -0.511984)
							(end 0.381 -0.3683)
						)
						(arc
							(start 0.381 0.3683)
							(mid 0.321484 0.511984)
							(end 0.1778 0.5715)
						)
					)
					(width 0)
					(fill yes)
				)
			)
		)
		(pad "G" smd custom
			(at -0.98425 0.9525 270)
			(size 0.1905 0.1905)
			(layers "F.Cu" "F.Mask" "F.Paste")
			(net "PCIE_MATED#_A")
			(options
				(clearance outline)
				(anchor circle)
			)
			(primitives
				(gr_poly
					(pts
						(arc
							(start -0.1778 0.5715)
							(mid -0.321484 0.511984)
							(end -0.381 0.3683)
						)
						(arc
							(start -0.381 -0.3683)
							(mid -0.321484 -0.511984)
							(end -0.1778 -0.5715)
						)
						(arc
							(start 0.1778 -0.5715)
							(mid 0.321484 -0.511984)
							(end 0.381 -0.3683)
						)
						(arc
							(start 0.381 0.3683)
							(mid 0.321484 0.511984)
							(end 0.1778 0.5715)
						)
					)
					(width 0)
					(fill yes)
				)
			)
		)
		(pad "S" smd custom
			(at 0.98425 0.9525 270)
			(size 0.1905 0.1905)
			(layers "F.Cu" "F.Mask" "F.Paste")
			(net "GND")
			(options
				(clearance outline)
				(anchor circle)
			)
			(primitives
				(gr_poly
					(pts
						(arc
							(start -0.1778 0.5715)
							(mid -0.321484 0.511984)
							(end -0.381 0.3683)
						)
						(arc
							(start -0.381 -0.3683)
							(mid -0.321484 -0.511984)
							(end -0.1778 -0.5715)
						)
						(arc
							(start 0.1778 -0.5715)
							(mid 0.321484 -0.511984)
							(end 0.381 -0.3683)
						)
						(arc
							(start 0.381 0.3683)
							(mid 0.321484 0.511984)
							(end 0.1778 0.5715)
						)
					)
					(width 0)
					(fill yes)
				)
			)
		)
	)
	(footprint ""
		(layer "F.Cu")
		(at 7.570216 -226.62388 180)
		(property "Reference" "R156"
			(at 0 0 180)
			(layer "F.SilkS")
			(hide yes)
			(effects
				(font
					(size 1.27 1.27)
				)
			)
		)
		(property "Value" "0R2J-2-GP"
			(at 0.064008 -3.993896 180)
			(unlocked yes)
			(layer "F.Fab")
			(hide yes)
			(effects
				(font
					(size 1.016 1.016)
					(thickness 0.1524)
				)
			)
		)
		(property "Device Type" "R402H16"
			(at 0.064008 -5.517896 180)
			(unlocked yes)
			(layer "F.Fab")
			(hide yes)
			(effects
				(font
					(size 1.016 1.016)
					(thickness 0.1524)
				)
			)
		)
		(duplicate_pad_numbers_are_jumpers no)
		(fp_line
			(start 0.508 -0.9398)
			(end -0.508 -0.9398)
			(stroke
				(width 0.1524)
				(type default)
			)
			(layer "F.SilkS")
		)
		(fp_line
			(start -0.508 -0.9398)
			(end -0.508 0.9398)
			(stroke
				(width 0.1524)
				(type default)
			)
			(layer "F.SilkS")
		)
		(fp_rect
			(start -0.508 0.9398)
			(end 0.508 -0.9398)
			(stroke
				(width 0)
				(type default)
			)
			(fill no)
			(layer "F.CrtYd")
		)
		(fp_rect
			(start -0.508 0.9398)
			(end 0.508 -0.9398)
			(stroke
				(width 0)
				(type default)
			)
			(fill no)
			(layer "F.Fab")
		)
		(pad "1" smd custom
			(at 0 -0.4445 180)
			(size 0.1397 0.1397)
			(layers "F.Cu" "F.Mask" "F.Paste")
			(net "PEER_TRAY_R")
			(options
				(clearance outline)
				(anchor circle)
			)
			(primitives
				(gr_poly
					(pts
						(arc
							(start -0.1778 -0.2794)
							(mid -0.249642 -0.249642)
							(end -0.2794 -0.1778)
						)
						(arc
							(start -0.2794 0.1778)
							(mid -0.249642 0.249642)
							(end -0.1778 0.2794)
						)
						(arc
							(start 0.1778 0.2794)
							(mid 0.249642 0.249642)
							(end 0.2794 0.1778)
						)
						(arc
							(start 0.2794 -0.1778)
							(mid 0.249642 -0.249642)
							(end 0.1778 -0.2794)
						)
					)
					(width 0)
					(fill yes)
				)
			)
		)
		(pad "2" smd custom
			(at 0 0.4445 180)
			(size 0.1397 0.1397)
			(layers "F.Cu" "F.Mask" "F.Paste")
			(net "PEER_TRAY")
			(options
				(clearance outline)
				(anchor circle)
			)
			(primitives
				(gr_poly
					(pts
						(arc
							(start -0.1778 -0.2794)
							(mid -0.249642 -0.249642)
							(end -0.2794 -0.1778)
						)
						(arc
							(start -0.2794 0.1778)
							(mid -0.249642 0.249642)
							(end -0.1778 0.2794)
						)
						(arc
							(start 0.1778 0.2794)
							(mid 0.249642 0.249642)
							(end 0.2794 0.1778)
						)
						(arc
							(start 0.2794 -0.1778)
							(mid 0.249642 -0.249642)
							(end 0.1778 -0.2794)
						)
					)
					(width 0)
					(fill yes)
				)
			)
		)
	)
)
